FILE_TYPE = CONNECTIVITY;
{Allegro Design Entry HDL 17.2-2016 S081 (4005846) 1/11/2022}
"PAGE_NUMBER" = 111;
0"NC";
1"P12V_S3_AUX_CPU1_NVDIMM\g";
2"P3V3_AUX\g";
3"P12V_S3_AUX_CPU1_NVDIMM\g";
4"P3V3_AUX\g";
5"GND\g";
6"GND\g";
7"GND\g";
8"GND\g";
9"GND\g";
10"M_G_CPU1_SA_DQ<31:0>";
11"M_G_CPU1_SA_CB<7:0>";
12"M_G_CPU1_SB_CB<7:0>";
13"M_G_CPU1_SA_CA<6:0>";
14"M_G_CPU1_SB_CA<6:0>";
15"M_G_CPU1_SB_DQ<31:0>";
16"M_G_CPU1_SB_DQS_DP<9:0>";
17"M_G_CPU1_SA_DQS_DP<9:0>";
18"M_G_CPU1_SB_DQS_DN<9:0>";
19"M_G_CPU1_SA_DQS_DN<9:0>";
20"I3C_SPD_DDREFGH_CPU1_LVC1_SCL_R6";
21"PD_CHG_CPU1_DIMM2_SAA";
22"I3C_SPD_DDREFGH_CPU1_LVC1_SDA";
23"M_G_CPU1_ALERT_N";
24"RST_M_GH_CPU1_FPGA_N";
25"I3C_SPD_DDREFGH_CPU1_LVC1_SCL";
26"PWRGD_CHG_CPU1_DIMM2";
27"TP_CHG_CPU1_DIMM2_FRU_6";
28"M_G_CPU1_SB_DQ<9>";
29"M_G_CPU1_SA_DQS_DN<9>";
30"M_G_CPU1_SA_DQS_DN<8>";
31"M_G_CPU1_SA_DQS_DN<7>";
32"M_G_CPU1_SA_DQS_DN<6>";
33"M_G_CPU1_SA_DQS_DN<5>";
34"M_G_CPU1_SA_DQS_DN<4>";
35"M_G_CPU1_SA_DQS_DN<3>";
36"M_G_CPU1_SA_DQS_DN<2>";
37"M_G_CPU1_SA_DQS_DN<1>";
38"M_G_CPU1_SA_DQS_DN<0>";
39"M_G_CPU1_SB_DQS_DN<9>";
40"M_G_CPU1_SB_DQS_DN<8>";
41"M_G_CPU1_SB_DQS_DN<7>";
42"M_G_CPU1_SB_DQS_DN<6>";
43"M_G_CPU1_SB_DQS_DN<5>";
44"M_G_CPU1_SB_DQS_DN<3>";
45"M_G_CPU1_SB_DQS_DN<4>";
46"M_G_CPU1_SB_DQS_DN<2>";
47"M_G_CPU1_SB_DQS_DN<1>";
48"M_G_CPU1_SB_DQS_DN<0>";
49"M_G_CPU1_SA_DQS_DP<9>";
50"M_G_CPU1_SA_DQS_DP<8>";
51"M_G_CPU1_SA_DQS_DP<7>";
52"M_G_CPU1_SA_DQS_DP<6>";
53"M_G_CPU1_SA_DQS_DP<5>";
54"M_G_CPU1_SA_DQS_DP<4>";
55"M_G_CPU1_SA_DQS_DP<3>";
56"M_G_CPU1_SA_DQS_DP<2>";
57"M_G_CPU1_SA_DQS_DP<1>";
58"M_G_CPU1_SA_DQS_DP<0>";
59"M_G_CPU1_SB_DQS_DP<9>";
60"M_G_CPU1_SB_DQS_DP<8>";
61"M_G_CPU1_SB_DQS_DP<7>";
62"M_G_CPU1_SB_DQS_DP<6>";
63"M_G_CPU1_SB_DQS_DP<5>";
64"M_G_CPU1_SB_DQS_DP<4>";
65"M_G_CPU1_SB_DQS_DP<3>";
66"M_G_CPU1_SB_DQS_DP<2>";
67"M_G_CPU1_SB_DQS_DP<1>";
68"M_G_CPU1_SB_DQS_DP<0>";
69"TP_CHG_CPU1_DIMM2_FRU_5";
70"M_G_CPU1_SB_PAR";
71"M_G_CPU1_SA_PAR";
72"M_G_CPU1_SA_DQ<18>";
73"M_G_CPU1_SA_DQ<21>";
74"M_G_CPU1_SA_DQ<24>";
75"M_G_CPU1_SA_CB<4>";
76"M_G_CPU1_SA_CB<3>";
77"M_G_CPU1_SB_DQ<17>";
78"TP_CHG_CPU1_DIMM2_FRU_0";
79"TP_CHG_CPU1_DIMM2_FRU_1";
80"TP_CHG_CPU1_DIMM2_FRU_2";
81"TP_CHG_CPU1_DIMM2_FRU_3";
82"TP_CHG_CPU1_DIMM2_FRU_4";
83"M_G_CPU1_SB_RSP<1>";
84"M_G_CPU1_SA_RSP<1>";
85"M_G_CPU1_SB_DQ<0>";
86"M_G_CPU1_SB_DQ<1>";
87"M_G_CPU1_SB_DQ<2>";
88"M_G_CPU1_SB_DQ<3>";
89"M_G_CPU1_SB_DQ<4>";
90"M_G_CPU1_SB_DQ<5>";
91"M_G_CPU1_SB_DQ<6>";
92"M_G_CPU1_SB_DQ<7>";
93"M_G_CPU1_SB_DQ<8>";
94"M_G_CPU1_SB_DQ<10>";
95"M_G_CPU1_SB_DQ<11>";
96"M_G_CPU1_SB_DQ<12>";
97"M_G_CPU1_SB_DQ<13>";
98"M_G_CPU1_SB_DQ<14>";
99"M_G_CPU1_SB_DQ<15>";
100"M_G_CPU1_SB_DQ<16>";
101"M_G_CPU1_SB_DQ<18>";
102"M_G_CPU1_SB_DQ<19>";
103"M_G_CPU1_SB_DQ<20>";
104"M_G_CPU1_SB_DQ<21>";
105"M_G_CPU1_SB_DQ<22>";
106"M_G_CPU1_SB_DQ<23>";
107"M_G_CPU1_SB_DQ<24>";
108"M_G_CPU1_SB_DQ<25>";
109"M_G_CPU1_SB_DQ<26>";
110"M_G_CPU1_SB_DQ<27>";
111"M_G_CPU1_SB_DQ<28>";
112"M_G_CPU1_SB_DQ<29>";
113"M_G_CPU1_SB_DQ<30>";
114"M_G_CPU1_SB_DQ<31>";
115"M_G_CPU1_SA_DQ<0>";
116"M_G_CPU1_SA_DQ<1>";
117"M_G_CPU1_SA_DQ<2>";
118"M_G_CPU1_SA_DQ<3>";
119"M_G_CPU1_SA_DQ<4>";
120"M_G_CPU1_SA_DQ<5>";
121"M_G_CPU1_SA_DQ<6>";
122"M_G_CPU1_SA_DQ<7>";
123"M_G_CPU1_SA_DQ<8>";
124"M_G_CPU1_SA_DQ<9>";
125"M_G_CPU1_SA_DQ<10>";
126"M_G_CPU1_SA_DQ<11>";
127"M_G_CPU1_SA_DQ<12>";
128"M_G_CPU1_SA_DQ<13>";
129"M_G_CPU1_SA_DQ<14>";
130"M_G_CPU1_SA_DQ<15>";
131"M_G_CPU1_SA_DQ<16>";
132"M_G_CPU1_SA_DQ<17>";
133"M_G_CPU1_SA_DQ<19>";
134"M_G_CPU1_SA_DQ<20>";
135"M_G_CPU1_SA_DQ<22>";
136"M_G_CPU1_SA_DQ<23>";
137"M_G_CPU1_SA_DQ<25>";
138"M_G_CPU1_SA_DQ<26>";
139"M_G_CPU1_SA_DQ<27>";
140"M_G_CPU1_SA_DQ<28>";
141"M_G_CPU1_SA_DQ<29>";
142"M_G_CPU1_SA_DQ<30>";
143"M_G_CPU1_SB_CS_N<3>";
144"M_G_CPU1_SA_CS_N<3>";
145"M_G_CPU1_SB_CS_N<2>";
146"M_G_CPU1_SA_CS_N<2>";
147"M_G_CPU1_CLK_DP<1>";
148"M_G_CPU1_CLK_DN<1>";
149"M_G_CPU1_SB_CB<0>";
150"M_G_CPU1_SB_CB<1>";
151"M_G_CPU1_SB_CB<2>";
152"M_G_CPU1_SB_CB<3>";
153"M_G_CPU1_SB_CB<4>";
154"M_G_CPU1_SB_CB<5>";
155"M_G_CPU1_SB_CB<6>";
156"M_G_CPU1_SA_CB<0>";
157"M_G_CPU1_SA_CB<2>";
158"M_G_CPU1_SA_CB<5>";
159"M_G_CPU1_SA_CB<6>";
160"M_G_CPU1_SB_CA<6>";
161"M_G_CPU1_SA_CA<6>";
162"M_G_CPU1_SB_CA<5>";
163"M_G_CPU1_SA_CA<5>";
164"M_G_CPU1_SB_CA<4>";
165"M_G_CPU1_SA_CA<4>";
166"M_G_CPU1_SB_CA<3>";
167"M_G_CPU1_SA_CA<3>";
168"M_G_CPU1_SB_CA<2>";
169"M_G_CPU1_SA_CA<2>";
170"M_G_CPU1_SB_CA<1>";
171"M_G_CPU1_SA_CA<1>";
172"M_G_CPU1_SB_CA<0>";
173"M_G_CPU1_SA_CA<0>";
174"M_G_CPU1_SB_CB<7>";
175"M_G_CPU1_SA_CB<1>";
176"M_G_CPU1_SA_CB<7>";
177"M_G_CPU1_SA_DQ<31>";
178"PD_CHG_CPU1_DIMM2_SAA";
%"TAP"
"1","(-1500,3000)","0","standard","I100";
;
CDS_LIB"standard"
BODY_TYPE"PLUMBING"
HDL_TAP"TRUE";
"B \NAC \NWC"10;
"S \NAC"
BN"3"118;
%"TAP"
"1","(-1500,3250)","0","standard","I102";
;
CDS_LIB"standard"
BODY_TYPE"PLUMBING"
HDL_TAP"TRUE";
"B \NAC \NWC"10;
"S \NAC"
BN"8"123;
%"TAP"
"1","(-1500,3200)","0","standard","I103";
;
CDS_LIB"standard"
BODY_TYPE"PLUMBING"
HDL_TAP"TRUE";
"B \NAC \NWC"10;
"S \NAC"
BN"7"122;
%"TAP"
"1","(-1500,3150)","0","standard","I104";
;
CDS_LIB"standard"
BODY_TYPE"PLUMBING"
HDL_TAP"TRUE";
"B \NAC \NWC"10;
"S \NAC"
BN"6"121;
%"TAP"
"1","(-1500,3350)","0","standard","I105";
;
CDS_LIB"standard"
BODY_TYPE"PLUMBING"
HDL_TAP"TRUE";
"B \NAC \NWC"10;
"S \NAC"
BN"10"125;
%"TAP"
"1","(-1500,3300)","0","standard","I106";
;
CDS_LIB"standard"
BODY_TYPE"PLUMBING"
HDL_TAP"TRUE";
"B \NAC \NWC"10;
"S \NAC"
BN"9"124;
%"TAP"
"1","(-1500,3500)","0","standard","I107";
;
CDS_LIB"standard"
BODY_TYPE"PLUMBING"
HDL_TAP"TRUE";
"B \NAC \NWC"10;
"S \NAC"
BN"13"128;
%"TAP"
"1","(-1500,3450)","0","standard","I108";
;
CDS_LIB"standard"
BODY_TYPE"PLUMBING"
HDL_TAP"TRUE";
"B \NAC \NWC"10;
"S \NAC"
BN"12"127;
%"TAP"
"1","(-1500,3400)","0","standard","I109";
;
CDS_LIB"standard"
BODY_TYPE"PLUMBING"
HDL_TAP"TRUE";
"B \NAC \NWC"10;
"S \NAC"
BN"11"126;
%"TAP"
"1","(-1500,3550)","0","standard","I110";
;
CDS_LIB"standard"
BODY_TYPE"PLUMBING"
HDL_TAP"TRUE";
"B \NAC \NWC"10;
"S \NAC"
BN"14"129;
%"TAP"
"1","(-1500,3600)","0","standard","I111";
;
CDS_LIB"standard"
BODY_TYPE"PLUMBING"
HDL_TAP"TRUE";
"B \NAC \NWC"10;
"S \NAC"
BN"15"130;
%"TAP"
"1","(-1500,3750)","0","standard","I112";
;
CDS_LIB"standard"
BODY_TYPE"PLUMBING"
HDL_TAP"TRUE";
"B \NAC \NWC"10;
"S \NAC"
BN"18"72;
%"TAP"
"1","(-1500,3700)","0","standard","I113";
;
CDS_LIB"standard"
BODY_TYPE"PLUMBING"
HDL_TAP"TRUE";
"B \NAC \NWC"10;
"S \NAC"
BN"17"132;
%"TAP"
"1","(-1500,3650)","0","standard","I114";
;
CDS_LIB"standard"
BODY_TYPE"PLUMBING"
HDL_TAP"TRUE";
"B \NAC \NWC"10;
"S \NAC"
BN"16"131;
%"TAP"
"1","(-1500,3800)","0","standard","I115";
;
CDS_LIB"standard"
BODY_TYPE"PLUMBING"
HDL_TAP"TRUE";
"B \NAC \NWC"10;
"S \NAC"
BN"19"133;
%"TAP"
"1","(-1500,3850)","0","standard","I116";
;
CDS_LIB"standard"
BODY_TYPE"PLUMBING"
HDL_TAP"TRUE";
"B \NAC \NWC"10;
"S \NAC"
BN"20"134;
%"TAP"
"1","(-1500,4000)","0","standard","I117";
;
CDS_LIB"standard"
BODY_TYPE"PLUMBING"
HDL_TAP"TRUE";
"B \NAC \NWC"10;
"S \NAC"
BN"23"136;
%"TAP"
"1","(-1500,3950)","0","standard","I118";
;
CDS_LIB"standard"
BODY_TYPE"PLUMBING"
HDL_TAP"TRUE";
"B \NAC \NWC"10;
"S \NAC"
BN"22"135;
%"TAP"
"1","(-1500,3900)","0","standard","I119";
;
CDS_LIB"standard"
BODY_TYPE"PLUMBING"
HDL_TAP"TRUE";
"B \NAC \NWC"10;
"S \NAC"
BN"21"73;
%"TAP"
"1","(-1500,4050)","0","standard","I120";
;
CDS_LIB"standard"
BODY_TYPE"PLUMBING"
HDL_TAP"TRUE";
"B \NAC \NWC"10;
"S \NAC"
BN"24"74;
%"TAP"
"1","(-1500,4100)","0","standard","I121";
;
CDS_LIB"standard"
BODY_TYPE"PLUMBING"
HDL_TAP"TRUE";
"B \NAC \NWC"10;
"S \NAC"
BN"25"137;
%"TAP"
"1","(-1500,4150)","0","standard","I122";
;
CDS_LIB"standard"
BODY_TYPE"PLUMBING"
HDL_TAP"TRUE";
"B \NAC \NWC"10;
"S \NAC"
BN"26"138;
%"TAP"
"1","(-1500,4200)","0","standard","I123";
;
CDS_LIB"standard"
BODY_TYPE"PLUMBING"
HDL_TAP"TRUE";
"B \NAC \NWC"10;
"S \NAC"
BN"27"139;
%"TAP"
"1","(-1500,4250)","0","standard","I124";
;
CDS_LIB"standard"
BODY_TYPE"PLUMBING"
HDL_TAP"TRUE";
"B \NAC \NWC"10;
"S \NAC"
BN"28"140;
%"TAP"
"1","(-1500,4400)","0","standard","I125";
;
CDS_LIB"standard"
BODY_TYPE"PLUMBING"
HDL_TAP"TRUE";
"B \NAC \NWC"10;
"S \NAC"
BN"31"177;
%"TAP"
"1","(-1500,4350)","0","standard","I126";
;
CDS_LIB"standard"
BODY_TYPE"PLUMBING"
HDL_TAP"TRUE";
"B \NAC \NWC"10;
"S \NAC"
BN"30"142;
%"TAP"
"1","(-1500,4300)","0","standard","I127";
;
CDS_LIB"standard"
BODY_TYPE"PLUMBING"
HDL_TAP"TRUE";
"B \NAC \NWC"10;
"S \NAC"
BN"29"141;
%"TAP"
"1","(1250,2450)","0","standard","I130";
;
CDS_LIB"standard"
BODY_TYPE"PLUMBING"
HDL_TAP"TRUE";
"B \NAC \NWC"16;
"S \NAC"
BN"0"68;
%"TAP"
"1","(1250,2550)","0","standard","I131";
;
CDS_LIB"standard"
BODY_TYPE"PLUMBING"
HDL_TAP"TRUE";
"B \NAC \NWC"16;
"S \NAC"
BN"1"67;
%"TAP"
"1","(1425,2500)","0","standard","I132";
;
CDS_LIB"standard"
BODY_TYPE"PLUMBING"
HDL_TAP"TRUE";
"B \NAC \NWC"18;
"S \NAC"
BN"1"47;
%"TAP"
"1","(1425,2600)","0","standard","I133";
;
CDS_LIB"standard"
BODY_TYPE"PLUMBING"
HDL_TAP"TRUE";
"B \NAC \NWC"18;
"S \NAC"
BN"2"46;
%"TAP"
"1","(1425,2400)","0","standard","I134";
;
CDS_LIB"standard"
BODY_TYPE"PLUMBING"
HDL_TAP"TRUE";
"B \NAC \NWC"18;
"S \NAC"
BN"0"48;
%"TAP"
"1","(1250,2650)","0","standard","I135";
;
CDS_LIB"standard"
BODY_TYPE"PLUMBING"
HDL_TAP"TRUE";
"B \NAC \NWC"16;
"S \NAC"
BN"2"66;
%"TAP"
"1","(1250,2750)","0","standard","I136";
;
CDS_LIB"standard"
BODY_TYPE"PLUMBING"
HDL_TAP"TRUE";
"B \NAC \NWC"16;
"S \NAC"
BN"3"65;
%"TAP"
"1","(1250,2850)","0","standard","I137";
;
CDS_LIB"standard"
BODY_TYPE"PLUMBING"
HDL_TAP"TRUE";
"B \NAC \NWC"16;
"S \NAC"
BN"4"64;
%"TAP"
"1","(1250,2950)","0","standard","I138";
;
CDS_LIB"standard"
BODY_TYPE"PLUMBING"
HDL_TAP"TRUE";
"B \NAC \NWC"16;
"S \NAC"
BN"5"63;
%"TAP"
"1","(1250,3050)","0","standard","I139";
;
CDS_LIB"standard"
BODY_TYPE"PLUMBING"
HDL_TAP"TRUE";
"B \NAC \NWC"16;
"S \NAC"
BN"6"62;
%"TAP"
"1","(1425,2700)","0","standard","I140";
;
CDS_LIB"standard"
BODY_TYPE"PLUMBING"
HDL_TAP"TRUE";
"B \NAC \NWC"18;
"S \NAC"
BN"3"44;
%"TAP"
"1","(1425,2800)","0","standard","I141";
;
CDS_LIB"standard"
BODY_TYPE"PLUMBING"
HDL_TAP"TRUE";
"B \NAC \NWC"18;
"S \NAC"
BN"4"45;
%"TAP"
"1","(1425,2900)","0","standard","I142";
;
CDS_LIB"standard"
BODY_TYPE"PLUMBING"
HDL_TAP"TRUE";
"B \NAC \NWC"18;
"S \NAC"
BN"5"43;
%"TAP"
"1","(1425,3000)","0","standard","I143";
;
CDS_LIB"standard"
BODY_TYPE"PLUMBING"
HDL_TAP"TRUE";
"B \NAC \NWC"18;
"S \NAC"
BN"6"42;
%"TAP"
"1","(1425,3100)","0","standard","I144";
;
CDS_LIB"standard"
BODY_TYPE"PLUMBING"
HDL_TAP"TRUE";
"B \NAC \NWC"18;
"S \NAC"
BN"7"41;
%"TAP"
"1","(1250,3150)","0","standard","I145";
;
CDS_LIB"standard"
BODY_TYPE"PLUMBING"
HDL_TAP"TRUE";
"B \NAC \NWC"16;
"S \NAC"
BN"7"61;
%"TAP"
"1","(1250,3250)","0","standard","I146";
;
CDS_LIB"standard"
BODY_TYPE"PLUMBING"
HDL_TAP"TRUE";
"B \NAC \NWC"16;
"S \NAC"
BN"8"60;
%"TAP"
"1","(1250,3350)","0","standard","I147";
;
CDS_LIB"standard"
BODY_TYPE"PLUMBING"
HDL_TAP"TRUE";
"B \NAC \NWC"16;
"S \NAC"
BN"9"59;
%"TAP"
"1","(1250,3500)","0","standard","I148";
;
CDS_LIB"standard"
BODY_TYPE"PLUMBING"
HDL_TAP"TRUE";
"B \NAC \NWC"17;
"S \NAC"
BN"0"58;
%"TAP"
"1","(1250,3600)","0","standard","I149";
;
CDS_LIB"standard"
BODY_TYPE"PLUMBING"
HDL_TAP"TRUE";
"B \NAC \NWC"17;
"S \NAC"
BN"1"57;
%"TAP"
"1","(1425,3200)","0","standard","I150";
;
CDS_LIB"standard"
BODY_TYPE"PLUMBING"
HDL_TAP"TRUE";
"B \NAC \NWC"18;
"S \NAC"
BN"8"40;
%"TAP"
"1","(1425,3300)","0","standard","I151";
;
CDS_LIB"standard"
BODY_TYPE"PLUMBING"
HDL_TAP"TRUE";
"B \NAC \NWC"18;
"S \NAC"
BN"9"39;
%"TAP"
"1","(1425,3550)","0","standard","I152";
;
CDS_LIB"standard"
BODY_TYPE"PLUMBING"
HDL_TAP"TRUE";
"B \NAC \NWC"19;
"S \NAC"
BN"1"37;
%"TAP"
"1","(1425,3450)","0","standard","I153";
;
CDS_LIB"standard"
BODY_TYPE"PLUMBING"
HDL_TAP"TRUE";
"B \NAC \NWC"19;
"S \NAC"
BN"0"38;
%"TAP"
"1","(1250,3700)","0","standard","I154";
;
CDS_LIB"standard"
BODY_TYPE"PLUMBING"
HDL_TAP"TRUE";
"B \NAC \NWC"17;
"S \NAC"
BN"2"56;
%"TAP"
"1","(1250,3800)","0","standard","I155";
;
CDS_LIB"standard"
BODY_TYPE"PLUMBING"
HDL_TAP"TRUE";
"B \NAC \NWC"17;
"S \NAC"
BN"3"55;
%"TAP"
"1","(1250,3900)","0","standard","I156";
;
CDS_LIB"standard"
BODY_TYPE"PLUMBING"
HDL_TAP"TRUE";
"B \NAC \NWC"17;
"S \NAC"
BN"4"54;
%"TAP"
"1","(1250,4000)","0","standard","I157";
;
CDS_LIB"standard"
BODY_TYPE"PLUMBING"
HDL_TAP"TRUE";
"B \NAC \NWC"17;
"S \NAC"
BN"5"53;
%"TAP"
"1","(1250,4100)","0","standard","I158";
;
CDS_LIB"standard"
BODY_TYPE"PLUMBING"
HDL_TAP"TRUE";
"B \NAC \NWC"17;
"S \NAC"
BN"6"52;
%"TAP"
"1","(1425,3650)","0","standard","I159";
;
CDS_LIB"standard"
BODY_TYPE"PLUMBING"
HDL_TAP"TRUE";
"B \NAC \NWC"19;
"S \NAC"
BN"2"36;
%"TAP"
"1","(1425,3750)","0","standard","I160";
;
CDS_LIB"standard"
BODY_TYPE"PLUMBING"
HDL_TAP"TRUE";
"B \NAC \NWC"19;
"S \NAC"
BN"3"35;
%"TAP"
"1","(1425,3850)","0","standard","I161";
;
CDS_LIB"standard"
BODY_TYPE"PLUMBING"
HDL_TAP"TRUE";
"B \NAC \NWC"19;
"S \NAC"
BN"4"34;
%"TAP"
"1","(1425,3950)","0","standard","I162";
;
CDS_LIB"standard"
BODY_TYPE"PLUMBING"
HDL_TAP"TRUE";
"B \NAC \NWC"19;
"S \NAC"
BN"5"33;
%"TAP"
"1","(1425,4050)","0","standard","I163";
;
CDS_LIB"standard"
BODY_TYPE"PLUMBING"
HDL_TAP"TRUE";
"B \NAC \NWC"19;
"S \NAC"
BN"6"32;
%"TAP"
"1","(1250,4200)","0","standard","I164";
;
CDS_LIB"standard"
BODY_TYPE"PLUMBING"
HDL_TAP"TRUE";
"B \NAC \NWC"17;
"S \NAC"
BN"7"51;
%"TAP"
"1","(1250,4300)","0","standard","I165";
;
CDS_LIB"standard"
BODY_TYPE"PLUMBING"
HDL_TAP"TRUE";
"B \NAC \NWC"17;
"S \NAC"
BN"8"50;
%"TAP"
"1","(1250,4400)","0","standard","I166";
;
CDS_LIB"standard"
BODY_TYPE"PLUMBING"
HDL_TAP"TRUE";
"B \NAC \NWC"17;
"S \NAC"
BN"9"49;
%"TAP"
"1","(1425,4150)","0","standard","I167";
;
CDS_LIB"standard"
BODY_TYPE"PLUMBING"
HDL_TAP"TRUE";
"B \NAC \NWC"19;
"S \NAC"
BN"7"31;
%"TAP"
"1","(1425,4250)","0","standard","I168";
;
CDS_LIB"standard"
BODY_TYPE"PLUMBING"
HDL_TAP"TRUE";
"B \NAC \NWC"19;
"S \NAC"
BN"8"30;
%"TAP"
"1","(1425,4350)","0","standard","I169";
;
CDS_LIB"standard"
BODY_TYPE"PLUMBING"
HDL_TAP"TRUE";
"B \NAC \NWC"19;
"S \NAC"
BN"9"29;
%"VCC_CORE"
"1","(2925,4950)","0","logical_power","I174";
;
HDL_POWER"P12V_S3_AUX_CPU1_NVDIMM"
CDS_LIB"logical_power";
"A"3;
%"SCONN288_ADR50017P087CC"
"3","(3775,2775)","0","pure_quanta","I178";
;
PART_NUMBER"DFHST8FS460"
MATERIAL"IO"
PART_TYPE"SMLF"
VALUE"SCONN288_ADR50017-P087CC"
$LOCATION"J30"
CDS_LIB"pure_quanta"
CDS_LMAN_SYM_OUTLINE"-450,1775,450,-1775"
NEEDS_NO_SIZE"TRUE"
CDS_LOCATION"J30"
$SEC"3"
CDS_SEC"3";
"G3"
$PN"G3"5;
"G2"
$PN"G2"5;
"G1"
$PN"G1"5;
"VSS62"
$PN"141"5;
"VSS61"
$PN"139"5;
"VSS60"
$PN"136"5;
"VSS58"
$PN"132"5;
"VSS104"
$PN"240"6;
"VSS102"
$PN"235"6;
"VSS100"
$PN"230"6;
"VIN_BULK2"
$PN"146"3;
"VIN_BULK1"
$PN"145"3;
"VIN_BULK0"
$PN"1"3;
"VSS126"
$PN"288"6;
"VSS125"
$PN"286"6;
"VSS124"
$PN"284"6;
"VSS123"
$PN"281"6;
"VSS122"
$PN"279"6;
"VSS121"
$PN"277"6;
"VSS120"
$PN"275"6;
"VSS119"
$PN"273"6;
"VSS118"
$PN"270"6;
"VSS117"
$PN"268"6;
"VSS116"
$PN"266"6;
"VSS115"
$PN"264"6;
"VSS114"
$PN"262"6;
"VSS113"
$PN"259"6;
"VSS112"
$PN"257"6;
"VSS111"
$PN"255"6;
"VSS110"
$PN"253"6;
"VSS109"
$PN"251"6;
"VSS108"
$PN"248"6;
"VSS107"
$PN"246"6;
"VSS106"
$PN"244"6;
"VSS105"
$PN"242"6;
"VSS103"
$PN"237"6;
"VSS101"
$PN"233"6;
"VSS99"
$PN"228"6;
"VSS98"
$PN"226"6;
"VSS97"
$PN"224"6;
"VSS96"
$PN"222"6;
"VSS95"
$PN"219"6;
"VSS94"
$PN"216"6;
"VSS93"
$PN"214"6;
"VSS92"
$PN"212"6;
"VSS91"
$PN"210"6;
"VSS90"
$PN"208"6;
"VSS89"
$PN"206"6;
"VSS88"
$PN"204"6;
"VSS87"
$PN"202"6;
"VSS86"
$PN"199"6;
"VSS85"
$PN"197"6;
"VSS84"
$PN"195"6;
"VSS83"
$PN"193"6;
"VSS82"
$PN"191"6;
"VSS81"
$PN"188"6;
"VSS80"
$PN"186"6;
"VSS79"
$PN"184"6;
"VSS78"
$PN"182"6;
"VSS77"
$PN"180"6;
"VSS76"
$PN"177"6;
"VSS75"
$PN"175"6;
"VSS74"
$PN"173"6;
"VSS73"
$PN"171"6;
"VSS72"
$PN"169"6;
"VSS71"
$PN"166"6;
"VSS70"
$PN"164"6;
"VSS69"
$PN"162"6;
"VSS68"
$PN"160"6;
"VSS67"
$PN"158"6;
"VSS66"
$PN"155"6;
"VSS65"
$PN"153"6;
"VSS64"
$PN"151"6;
"VSS63"
$PN"143"5;
"VSS59"
$PN"134"5;
"VSS57"
$PN"130"5;
"VSS56"
$PN"128"5;
"VSS55"
$PN"125"5;
"VSS54"
$PN"123"5;
"VSS53"
$PN"121"5;
"VSS52"
$PN"119"5;
"VSS51"
$PN"117"5;
"VSS50"
$PN"114"5;
"VSS49"
$PN"112"5;
"VSS48"
$PN"110"5;
"VSS47"
$PN"108"5;
"VSS46"
$PN"106"5;
"VSS45"
$PN"103"5;
"VSS44"
$PN"101"5;
"VSS43"
$PN"99"5;
"VSS42"
$PN"97"5;
"VSS41"
$PN"95"5;
"VSS40"
$PN"92"5;
"VSS39"
$PN"90"5;
"VSS38"
$PN"88"5;
"VSS37"
$PN"85"5;
"VSS36"
$PN"83"5;
"VSS35"
$PN"81"5;
"VSS34"
$PN"79"5;
"VSS33"
$PN"77"5;
"VSS32"
$PN"75"5;
"VSS31"
$PN"73"5;
"VSS30"
$PN"71"5;
"VSS29"
$PN"69"5;
"VSS28"
$PN"67"5;
"VSS27"
$PN"65"5;
"VSS26"
$PN"63"5;
"VSS25"
$PN"61"5;
"VSS24"
$PN"59"5;
"VSS23"
$PN"57"5;
"VSS22"
$PN"54"5;
"VSS21"
$PN"52"5;
"VSS20"
$PN"50"5;
"VSS19"
$PN"48"5;
"VSS18"
$PN"46"5;
"VSS17"
$PN"43"5;
"VSS16"
$PN"41"5;
"VSS15"
$PN"39"5;
"VSS14"
$PN"37"5;
"VSS13"
$PN"35"5;
"VSS12"
$PN"32"5;
"VSS11"
$PN"30"5;
"VSS10"
$PN"28"5;
"VSS9"
$PN"26"5;
"VSS8"
$PN"24"5;
"VSS7"
$PN"21"5;
"VSS6"
$PN"19"5;
"VSS5"
$PN"17"5;
"VSS4"
$PN"15"5;
"VSS3"
$PN"13"5;
"VSS2"
$PN"10"5;
"VSS1"
$PN"8"5;
"VSS0"
$PN"6"5;
%"SCONN288_ADR50017P087CC"
"1","(-2325,2675)","0","pure_quanta","I179";
;
PART_NUMBER"DFHST8FS460"
PART_TYPE"SMLF"
MATERIAL"IO"
VALUE"SCONN288_ADR50017-P087CC"
$LOCATION"J30"
CDS_LIB"pure_quanta"
CDS_LMAN_SYM_OUTLINE"-450,1875,450,-1875"
NEEDS_NO_SIZE"TRUE"
CDS_LOCATION"J30"
$SEC"1"
CDS_SEC"1";
"DQ31_A"
$PN"194"177;
"CB7_A"
$PN"205"176;
"CB4_A"
$PN"58"75;
"CB1_A"
$PN"53"175;
"CB7_B"
$PN"236"174;
"ALERT_N \B"
$PN"62"23;
"CA0_A"
$PN"66"173;
"CA0_B"
$PN"76"172;
"CA1_A"
$PN"211"171;
"CA1_B"
$PN"221"170;
"CA2_A"
$PN"68"169;
"CA2_B"
$PN"78"168;
"CA3_A"
$PN"213"167;
"CA3_B"
$PN"223"166;
"CA4_A"
$PN"70"165;
"CA4_B"
$PN"80"164;
"CA5_A"
$PN"215"163;
"CA5_B"
$PN"225"162;
"CA6_A"
$PN"72"161;
"CA6_B"
$PN"82"160;
"CB6_A"
$PN"203"159;
"CB5_A"
$PN"60"158;
"CB3_A"
$PN"198"76;
"CB2_A"
$PN"196"157;
"CB0_A"
$PN"51"156;
"CB6_B"
$PN"234"155;
"CB5_B"
$PN"91"154;
"CB4_B"
$PN"89"153;
"CB3_B"
$PN"243"152;
"CB2_B"
$PN"241"151;
"CB1_B"
$PN"98"150;
"CB0_B"
$PN"96"149;
"CK_C \B"
$PN"218"148;
"CK_T"
$PN"217"147;
"CS0_A_N"
$PN"64"146;
"CS0_B_N"
$PN"84"145;
"CS1_A_N"
$PN"209"144;
"CS1_B_N"
$PN"229"143;
"DQ30_A"
$PN"192"142;
"DQ29_A"
$PN"49"141;
"DQ28_A"
$PN"47"140;
"DQ27_A"
$PN"187"139;
"DQ26_A"
$PN"185"138;
"DQ25_A"
$PN"42"137;
"DQ24_A"
$PN"40"74;
"DQ23_A"
$PN"183"136;
"DQ22_A"
$PN"181"135;
"DQ21_A"
$PN"38"73;
"DQ20_A"
$PN"36"134;
"DQ19_A"
$PN"176"133;
"DQ18_A"
$PN"174"72;
"DQ17_A"
$PN"31"132;
"DQ16_A"
$PN"29"131;
"DQ15_A"
$PN"172"130;
"DQ14_A"
$PN"170"129;
"DQ13_A"
$PN"27"128;
"DQ12_A"
$PN"25"127;
"DQ11_A"
$PN"165"126;
"DQ10_A"
$PN"163"125;
"DQ9_A"
$PN"20"124;
"DQ8_A"
$PN"18"123;
"DQ7_A"
$PN"161"122;
"DQ6_A"
$PN"159"121;
"DQ5_A"
$PN"16"120;
"DQ4_A"
$PN"14"119;
"DQ3_A"
$PN"154"118;
"DQ2_A"
$PN"152"117;
"DQ1_A"
$PN"9"116;
"DQ0_A"
$PN"7"115;
"DQ31_B"
$PN"287"114;
"DQ30_B"
$PN"285"113;
"DQ29_B"
$PN"142"112;
"DQ28_B"
$PN"140"111;
"DQ27_B"
$PN"280"110;
"DQ26_B"
$PN"278"109;
"DQ25_B"
$PN"135"108;
"DQ24_B"
$PN"133"107;
"DQ23_B"
$PN"276"106;
"DQ22_B"
$PN"274"105;
"DQ21_B"
$PN"131"104;
"DQ20_B"
$PN"129"103;
"DQ19_B"
$PN"269"102;
"DQ18_B"
$PN"267"101;
"DQ17_B"
$PN"124"77;
"DQ16_B"
$PN"122"100;
"DQ15_B"
$PN"265"99;
"DQ14_B"
$PN"263"98;
"DQ13_B"
$PN"120"97;
"DQ12_B"
$PN"118"96;
"DQ11_B"
$PN"258"95;
"DQ10_B"
$PN"256"94;
"DQ9_B"
$PN"113"28;
"DQ8_B"
$PN"111"93;
"DQ7_B"
$PN"254"92;
"DQ6_B"
$PN"252"91;
"DQ5_B"
$PN"109"90;
"DQ4_B"
$PN"107"89;
"DQ3_B"
$PN"247"88;
"DQ2_B"
$PN"245"87;
"DQ1_B"
$PN"102"86;
"DQ0_B"
$PN"100"85;
"HSA"
$PN"148"21;
"HSCL"
$PN"4"20;
"HSDA"
$PN"5"22;
"LBD||RSP_A_N"
$PN"86"84;
"LBS||RSP_B_N"
$PN"87"83;
"PAR_A"
$PN"74"71;
"PAR_B"
$PN"227"70;
"PWR_GOOD||FAIL_N"
$PN"147"26;
"RESET_N \B"
$PN"207"24;
"RFU6"
$PN"232"27;
"RFU5"
$PN"231"69;
"RFU4"
$PN"220"82;
"RFU3"
$PN"150"81;
"RFU2"
$PN"149"80;
"RFU1"
$PN"144"79;
"RFU0"
$PN"2"78;
"VIN_MGMT"
$PN"3"4;
%"SCONN288_ADR50017P087CC"
"2","(350,3400)","0","pure_quanta","I180";
;
PART_NUMBER"DFHST8FS460"
PART_TYPE"SMLF"
VALUE"SCONN288_ADR50017-P087CC"
MATERIAL"IO"
LOCATION"J30"
CDS_LIB"pure_quanta"
CDS_LMAN_SYM_OUTLINE"-600,1150,600,-1150"
NEEDS_NO_SIZE"TRUE"
$SEC"2"
CDS_SEC"2";
"DQS7_A_C||TDQS7_A_C \B"
$PN"178"31;
"DQS6_A_T||TDQS6_A_T"
$PN"168"52;
"DQS8_B_T||TDQS8_B_T"
$PN"283"60;
"DQS8_B_C||TDQS8_B_C \B"
$PN"282"40;
"DQS7_B_T||TDQS7_B_T"
$PN"272"61;
"DQS0_A_C \B"
$PN"12"38;
"DQS0_A_T"
$PN"11"58;
"DQS0_B_C \B"
$PN"105"48;
"DQS0_B_T"
$PN"104"68;
"DQS1_A_C \B"
$PN"23"37;
"DQS1_A_T"
$PN"22"57;
"DQS1_B_C \B"
$PN"116"47;
"DQS1_B_T"
$PN"115"67;
"DQS2_A_C \B"
$PN"34"36;
"DQS2_A_T"
$PN"33"56;
"DQS2_B_C \B"
$PN"127"46;
"DQS2_B_T"
$PN"126"66;
"DQS3_A_C \B"
$PN"45"35;
"DQS3_A_T"
$PN"44"55;
"DQS3_B_C \B"
$PN"138"44;
"DQS3_B_T"
$PN"137"65;
"DQS4_A_C \B"
$PN"56"34;
"DQS4_A_T"
$PN"55"54;
"DQS4_B_C \B"
$PN"238"45;
"DQS4_B_T"
$PN"239"64;
"DQS5_A_C||TDQS5_A_C||DQS5_A_T||TDQS5_A_T \B"
$PN"156"33;
"DQS5_A_T||TDQS5_A_T"
$PN"157"53;
"DQS5_B_C||TDQS5_B_C \B"
$PN"249"43;
"DQS5_B_T||TDQS5_B_T"
$PN"250"63;
"DQS6_A_C||TDQS6_A_C||DQS6_A_T||TDQS6_A_T \B"
$PN"167"32;
"DQS6_B_C||TDQS6_B_C \B"
$PN"260"42;
"DQS6_B_T||TDQS6_B_T"
$PN"261"62;
"DQS7_A_T||TDQS7_A_T"
$PN"179"51;
"DQS7_B_C||TDQS7_B_C \B"
$PN"271"41;
"DQS8_A_C||TDQS8_A_C \B"
$PN"189"30;
"DQS8_A_T||TDQS8_A_T"
$PN"190"50;
"DQS9_A_C||TDQS9_A_C \B"
$PN"200"29;
"DQS9_A_T||TDQS9_A_T"
$PN"201"49;
"DQS9_B_C||TDQS9_B_C \B"
$PN"94"39;
"DQS9_B_T||TDQS9_B_T||DBI4_B_N"
$PN"93"59;
%"Q_RES"
"1","(-4150,1675)","0","pure_quanta","I182";
;
PART_NUMBER"CS04992FB07"
VALUE"49.9"
MATERIAL"CHIP"
$LOCATION"R3904"
CDS_LIB"pure_quanta"
PACK_TYPE"0402LF"
TOLERANCE"1%"
WATTAGE"1/16W"
CDS_LOCATION"R3904"
$SEC"1"
CDS_SEC"1";
"B"
$PN"2"25;
"A"
$PN"1"20;
%"VCC_CORE"
"1","(-3975,2275)","0","logical_power","I22";
;
HDL_POWER"P3V3_AUX"
CDS_LIB"logical_power";
"A"4;
%"TAP"
"1","(-3150,2200)","2","standard","I23";
;
CDS_LIB"standard"
BODY_TYPE"PLUMBING"
HDL_TAP"TRUE";
"B \NAC \NWC"12;
"S \NAC"
BN"0"149;
%"TAP"
"1","(-3150,2250)","2","standard","I24";
;
CDS_LIB"standard"
BODY_TYPE"PLUMBING"
HDL_TAP"TRUE";
"B \NAC \NWC"12;
"S \NAC"
BN"1"150;
%"TAP"
"1","(-3150,2300)","2","standard","I25";
;
CDS_LIB"standard"
BODY_TYPE"PLUMBING"
HDL_TAP"TRUE";
"B \NAC \NWC"12;
"S \NAC"
BN"2"151;
%"TAP"
"1","(-3150,2350)","2","standard","I26";
;
CDS_LIB"standard"
BODY_TYPE"PLUMBING"
HDL_TAP"TRUE";
"B \NAC \NWC"12;
"S \NAC"
BN"3"152;
%"TAP"
"1","(-3150,2400)","2","standard","I27";
;
CDS_LIB"standard"
BODY_TYPE"PLUMBING"
HDL_TAP"TRUE";
"B \NAC \NWC"12;
"S \NAC"
BN"4"153;
%"TAP"
"1","(-3150,2450)","2","standard","I28";
;
CDS_LIB"standard"
BODY_TYPE"PLUMBING"
HDL_TAP"TRUE";
"B \NAC \NWC"12;
"S \NAC"
BN"5"154;
%"TAP"
"1","(-3150,2500)","2","standard","I29";
;
CDS_LIB"standard"
BODY_TYPE"PLUMBING"
HDL_TAP"TRUE";
"B \NAC \NWC"12;
"S \NAC"
BN"6"155;
%"TAP"
"1","(-3150,2550)","2","standard","I30";
;
CDS_LIB"standard"
BODY_TYPE"PLUMBING"
HDL_TAP"TRUE";
"B \NAC \NWC"12;
"S \NAC"
BN"7"174;
%"TAP"
"1","(-3150,2700)","2","standard","I31";
;
CDS_LIB"standard"
BODY_TYPE"PLUMBING"
HDL_TAP"TRUE";
"B \NAC \NWC"11;
"S \NAC"
BN"1"175;
%"TAP"
"1","(-3150,2650)","2","standard","I32";
;
CDS_LIB"standard"
BODY_TYPE"PLUMBING"
HDL_TAP"TRUE";
"B \NAC \NWC"11;
"S \NAC"
BN"0"156;
%"TAP"
"1","(-3150,2750)","2","standard","I33";
;
CDS_LIB"standard"
BODY_TYPE"PLUMBING"
HDL_TAP"TRUE";
"B \NAC \NWC"11;
"S \NAC"
BN"2"157;
%"TAP"
"1","(-3150,2800)","2","standard","I34";
;
CDS_LIB"standard"
BODY_TYPE"PLUMBING"
HDL_TAP"TRUE";
"B \NAC \NWC"11;
"S \NAC"
BN"3"76;
%"TAP"
"1","(-3150,2850)","2","standard","I35";
;
CDS_LIB"standard"
BODY_TYPE"PLUMBING"
HDL_TAP"TRUE";
"B \NAC \NWC"11;
"S \NAC"
BN"4"75;
%"TAP"
"1","(-3150,2900)","2","standard","I36";
;
CDS_LIB"standard"
BODY_TYPE"PLUMBING"
HDL_TAP"TRUE";
"B \NAC \NWC"11;
"S \NAC"
BN"5"158;
%"TAP"
"1","(-3150,2950)","2","standard","I37";
;
CDS_LIB"standard"
BODY_TYPE"PLUMBING"
HDL_TAP"TRUE";
"B \NAC \NWC"11;
"S \NAC"
BN"6"159;
%"TAP"
"1","(-3150,3000)","2","standard","I38";
;
CDS_LIB"standard"
BODY_TYPE"PLUMBING"
HDL_TAP"TRUE";
"B \NAC \NWC"11;
"S \NAC"
BN"7"176;
%"TAP"
"1","(-3150,3750)","2","standard","I39";
;
CDS_LIB"standard"
BODY_TYPE"PLUMBING"
HDL_TAP"TRUE";
"B \NAC \NWC"14;
"S \NAC"
BN"1"170;
%"UNIVERSAL_GND"
"1","(-2925,25)","0","logical_power","I4";
;
HDL_POWER"GND"
CDS_LIB"logical_power";
"A"9;
%"TAP"
"1","(-3150,3700)","2","standard","I40";
;
CDS_LIB"standard"
BODY_TYPE"PLUMBING"
HDL_TAP"TRUE";
"B \NAC \NWC"14;
"S \NAC"
BN"0"172;
%"TAP"
"1","(-3150,3800)","2","standard","I41";
;
CDS_LIB"standard"
BODY_TYPE"PLUMBING"
HDL_TAP"TRUE";
"B \NAC \NWC"14;
"S \NAC"
BN"2"168;
%"TAP"
"1","(-3150,3850)","2","standard","I42";
;
CDS_LIB"standard"
BODY_TYPE"PLUMBING"
HDL_TAP"TRUE";
"B \NAC \NWC"14;
"S \NAC"
BN"3"166;
%"TAP"
"1","(-3150,3900)","2","standard","I43";
;
CDS_LIB"standard"
BODY_TYPE"PLUMBING"
HDL_TAP"TRUE";
"B \NAC \NWC"14;
"S \NAC"
BN"4"164;
%"TAP"
"1","(-3150,3950)","2","standard","I44";
;
CDS_LIB"standard"
BODY_TYPE"PLUMBING"
HDL_TAP"TRUE";
"B \NAC \NWC"14;
"S \NAC"
BN"5"162;
%"TAP"
"1","(-3150,4000)","2","standard","I45";
;
CDS_LIB"standard"
BODY_TYPE"PLUMBING"
HDL_TAP"TRUE";
"B \NAC \NWC"14;
"S \NAC"
BN"6"160;
%"TAP"
"1","(-3150,4100)","2","standard","I46";
;
CDS_LIB"standard"
BODY_TYPE"PLUMBING"
HDL_TAP"TRUE";
"B \NAC \NWC"13;
"S \NAC"
BN"0"173;
%"TAP"
"1","(-3150,4150)","2","standard","I47";
;
CDS_LIB"standard"
BODY_TYPE"PLUMBING"
HDL_TAP"TRUE";
"B \NAC \NWC"13;
"S \NAC"
BN"1"171;
%"TAP"
"1","(-3150,4200)","2","standard","I48";
;
CDS_LIB"standard"
BODY_TYPE"PLUMBING"
HDL_TAP"TRUE";
"B \NAC \NWC"13;
"S \NAC"
BN"2"169;
%"TAP"
"1","(-3150,4250)","2","standard","I49";
;
CDS_LIB"standard"
BODY_TYPE"PLUMBING"
HDL_TAP"TRUE";
"B \NAC \NWC"13;
"S \NAC"
BN"3"167;
%"Q_RES"
"2","(-2925,250)","0","pure_quanta","I5";
;
PART_NUMBER"CS38452FB05"
WATTAGE"1/16W"
MATERIAL"CHIP"
TOLERANCE"1%"
PACK_TYPE"0402LF"
VALUE"84.5K"
$LOCATION"R74"
CDS_LIB"pure_quanta"
$LOCATION"R74"
CDS_LOCATION"R74"
$SEC"1"
CDS_SEC"1";
"A"
$PN"1"178;
"B"
$PN"2"9;
%"TAP"
"1","(-3150,4350)","2","standard","I50";
;
CDS_LIB"standard"
BODY_TYPE"PLUMBING"
HDL_TAP"TRUE";
"B \NAC \NWC"13;
"S \NAC"
BN"5"163;
%"TAP"
"1","(-3150,4300)","2","standard","I51";
;
CDS_LIB"standard"
BODY_TYPE"PLUMBING"
HDL_TAP"TRUE";
"B \NAC \NWC"13;
"S \NAC"
BN"4"165;
%"TAP"
"1","(-3150,4400)","2","standard","I52";
;
CDS_LIB"standard"
BODY_TYPE"PLUMBING"
HDL_TAP"TRUE";
"B \NAC \NWC"13;
"S \NAC"
BN"6"161;
%"UNIVERSAL_GND"
"1","(225,150)","0","logical_power","I53";
;
HDL_POWER"GND"
CDS_LIB"logical_power";
"A"8;
%"Q_CAP"
"1","(225,525)","0","pure_quanta","I54";
;
PART_NUMBER"CH5221MEB00"
VOLTAGE"6.3V"
TOLERANCE"20%"
PACK_TYPE"C0402"
MATERIAL"X6S"
VALUE"2.2UF"
$LOCATION"C78"
CDS_LIB"pure_quanta"
$LOCATION"C78"
CDS_LOCATION"C78"
$SEC"1"
CDS_SEC"1";
"B"
$PN"2"8;
"A"
$PN"1"2;
%"VCC_CORE"
"1","(225,850)","0","logical_power","I55";
;
HDL_POWER"P3V3_AUX"
CDS_LIB"logical_power";
"A"2;
%"Q_CAP"
"1","(1225,525)","0","pure_quanta","I56";
;
PART_NUMBER"CH6103KEA00"
MATERIAL"X6S"
VOLTAGE"16V"
TOLERANCE"10%"
VALUE"10UF"
PACK_TYPE"C0805"
$LOCATION"C79"
CDS_LIB"pure_quanta"
$LOCATION"C79"
CDS_LOCATION"C79"
$SEC"1"
CDS_SEC"1";
"B"
$PN"2"7;
"A"
$PN"1"1;
%"VCC_CORE"
"1","(1225,850)","0","logical_power","I57";
;
HDL_POWER"P12V_S3_AUX_CPU1_NVDIMM"
CDS_LIB"logical_power";
"A"1;
%"UNIVERSAL_GND"
"1","(1850,150)","0","logical_power","I58";
;
HDL_POWER"GND"
CDS_LIB"logical_power";
"A"7;
%"Q_CAP"
"1","(1850,525)","0","pure_quanta","I59";
;
PART_NUMBER"CH6103KEA00"
MATERIAL"X6S"
VALUE"10UF"
PACK_TYPE"C0805"
VOLTAGE"16V"
TOLERANCE"10%"
$LOCATION"C80"
CDS_LIB"pure_quanta"
$LOCATION"C80"
CDS_LOCATION"C80"
$SEC"1"
CDS_SEC"1";
"B"
$PN"2"7;
"A"
$PN"1"1;
%"UNIVERSAL_GND"
"1","(2925,700)","0","logical_power","I60";
;
HDL_POWER"GND"
CDS_LIB"logical_power";
"A"6;
%"UNIVERSAL_GND"
"1","(4625,700)","0","logical_power","I62";
;
HDL_POWER"GND"
CDS_LIB"logical_power";
"A"5;
%"TAP"
"1","(-1500,1200)","0","standard","I63";
;
CDS_LIB"standard"
BODY_TYPE"PLUMBING"
HDL_TAP"TRUE";
"B \NAC \NWC"15;
"S \NAC"
BN"0"85;
%"TAP"
"1","(-1500,1300)","0","standard","I64";
;
CDS_LIB"standard"
BODY_TYPE"PLUMBING"
HDL_TAP"TRUE";
"B \NAC \NWC"15;
"S \NAC"
BN"2"87;
%"TAP"
"1","(-1500,1250)","0","standard","I65";
;
CDS_LIB"standard"
BODY_TYPE"PLUMBING"
HDL_TAP"TRUE";
"B \NAC \NWC"15;
"S \NAC"
BN"1"86;
%"TAP"
"1","(-1500,1400)","0","standard","I66";
;
CDS_LIB"standard"
BODY_TYPE"PLUMBING"
HDL_TAP"TRUE";
"B \NAC \NWC"15;
"S \NAC"
BN"4"89;
%"TAP"
"1","(-1500,1450)","0","standard","I67";
;
CDS_LIB"standard"
BODY_TYPE"PLUMBING"
HDL_TAP"TRUE";
"B \NAC \NWC"15;
"S \NAC"
BN"5"90;
%"TAP"
"1","(-1500,1350)","0","standard","I68";
;
CDS_LIB"standard"
BODY_TYPE"PLUMBING"
HDL_TAP"TRUE";
"B \NAC \NWC"15;
"S \NAC"
BN"3"88;
%"TAP"
"1","(-1500,1550)","0","standard","I69";
;
CDS_LIB"standard"
BODY_TYPE"PLUMBING"
HDL_TAP"TRUE";
"B \NAC \NWC"15;
"S \NAC"
BN"7"92;
%"TAP"
"1","(-1500,1500)","0","standard","I70";
;
CDS_LIB"standard"
BODY_TYPE"PLUMBING"
HDL_TAP"TRUE";
"B \NAC \NWC"15;
"S \NAC"
BN"6"91;
%"TAP"
"1","(-1500,1700)","0","standard","I71";
;
CDS_LIB"standard"
BODY_TYPE"PLUMBING"
HDL_TAP"TRUE";
"B \NAC \NWC"15;
"S \NAC"
BN"10"94;
%"TAP"
"1","(-1500,1650)","0","standard","I72";
;
CDS_LIB"standard"
BODY_TYPE"PLUMBING"
HDL_TAP"TRUE";
"B \NAC \NWC"15;
"S \NAC"
BN"9"28;
%"TAP"
"1","(-1500,1600)","0","standard","I73";
;
CDS_LIB"standard"
BODY_TYPE"PLUMBING"
HDL_TAP"TRUE";
"B \NAC \NWC"15;
"S \NAC"
BN"8"93;
%"TAP"
"1","(-1500,1750)","0","standard","I74";
;
CDS_LIB"standard"
BODY_TYPE"PLUMBING"
HDL_TAP"TRUE";
"B \NAC \NWC"15;
"S \NAC"
BN"11"95;
%"TAP"
"1","(-1500,1800)","0","standard","I75";
;
CDS_LIB"standard"
BODY_TYPE"PLUMBING"
HDL_TAP"TRUE";
"B \NAC \NWC"15;
"S \NAC"
BN"12"96;
%"TAP"
"1","(-1500,1950)","0","standard","I76";
;
CDS_LIB"standard"
BODY_TYPE"PLUMBING"
HDL_TAP"TRUE";
"B \NAC \NWC"15;
"S \NAC"
BN"15"99;
%"TAP"
"1","(-1500,1900)","0","standard","I77";
;
CDS_LIB"standard"
BODY_TYPE"PLUMBING"
HDL_TAP"TRUE";
"B \NAC \NWC"15;
"S \NAC"
BN"14"98;
%"TAP"
"1","(-1500,1850)","0","standard","I78";
;
CDS_LIB"standard"
BODY_TYPE"PLUMBING"
HDL_TAP"TRUE";
"B \NAC \NWC"15;
"S \NAC"
BN"13"97;
%"TAP"
"1","(-1500,2000)","0","standard","I79";
;
CDS_LIB"standard"
BODY_TYPE"PLUMBING"
HDL_TAP"TRUE";
"B \NAC \NWC"15;
"S \NAC"
BN"16"100;
%"TAP"
"1","(-1500,2050)","0","standard","I80";
;
CDS_LIB"standard"
BODY_TYPE"PLUMBING"
HDL_TAP"TRUE";
"B \NAC \NWC"15;
"S \NAC"
BN"17"77;
%"TAP"
"1","(-1500,2150)","0","standard","I81";
;
CDS_LIB"standard"
BODY_TYPE"PLUMBING"
HDL_TAP"TRUE";
"B \NAC \NWC"15;
"S \NAC"
BN"19"102;
%"TAP"
"1","(-1500,2200)","0","standard","I82";
;
CDS_LIB"standard"
BODY_TYPE"PLUMBING"
HDL_TAP"TRUE";
"B \NAC \NWC"15;
"S \NAC"
BN"20"103;
%"TAP"
"1","(-1500,2100)","0","standard","I83";
;
CDS_LIB"standard"
BODY_TYPE"PLUMBING"
HDL_TAP"TRUE";
"B \NAC \NWC"15;
"S \NAC"
BN"18"101;
%"TAP"
"1","(-1500,2350)","0","standard","I84";
;
CDS_LIB"standard"
BODY_TYPE"PLUMBING"
HDL_TAP"TRUE";
"B \NAC \NWC"15;
"S \NAC"
BN"23"106;
%"TAP"
"1","(-1500,2300)","0","standard","I85";
;
CDS_LIB"standard"
BODY_TYPE"PLUMBING"
HDL_TAP"TRUE";
"B \NAC \NWC"15;
"S \NAC"
BN"22"105;
%"TAP"
"1","(-1500,2250)","0","standard","I86";
;
CDS_LIB"standard"
BODY_TYPE"PLUMBING"
HDL_TAP"TRUE";
"B \NAC \NWC"15;
"S \NAC"
BN"21"104;
%"TAP"
"1","(-1500,2400)","0","standard","I87";
;
CDS_LIB"standard"
BODY_TYPE"PLUMBING"
HDL_TAP"TRUE";
"B \NAC \NWC"15;
"S \NAC"
BN"24"107;
%"TAP"
"1","(-1500,2450)","0","standard","I88";
;
CDS_LIB"standard"
BODY_TYPE"PLUMBING"
HDL_TAP"TRUE";
"B \NAC \NWC"15;
"S \NAC"
BN"25"108;
%"TAP"
"1","(-1500,2500)","0","standard","I89";
;
CDS_LIB"standard"
BODY_TYPE"PLUMBING"
HDL_TAP"TRUE";
"B \NAC \NWC"15;
"S \NAC"
BN"26"109;
%"TAP"
"1","(-1500,2600)","0","standard","I90";
;
CDS_LIB"standard"
BODY_TYPE"PLUMBING"
HDL_TAP"TRUE";
"B \NAC \NWC"15;
"S \NAC"
BN"28"111;
%"TAP"
"1","(-1500,2550)","0","standard","I91";
;
CDS_LIB"standard"
BODY_TYPE"PLUMBING"
HDL_TAP"TRUE";
"B \NAC \NWC"15;
"S \NAC"
BN"27"110;
%"TAP"
"1","(-1500,2700)","0","standard","I92";
;
CDS_LIB"standard"
BODY_TYPE"PLUMBING"
HDL_TAP"TRUE";
"B \NAC \NWC"15;
"S \NAC"
BN"30"113;
%"TAP"
"1","(-1500,2650)","0","standard","I93";
;
CDS_LIB"standard"
BODY_TYPE"PLUMBING"
HDL_TAP"TRUE";
"B \NAC \NWC"15;
"S \NAC"
BN"29"112;
%"TAP"
"1","(-1500,2850)","0","standard","I94";
;
CDS_LIB"standard"
BODY_TYPE"PLUMBING"
HDL_TAP"TRUE";
"B \NAC \NWC"10;
"S \NAC"
BN"0"115;
%"TAP"
"1","(-1500,2750)","0","standard","I95";
;
CDS_LIB"standard"
BODY_TYPE"PLUMBING"
HDL_TAP"TRUE";
"B \NAC \NWC"15;
"S \NAC"
BN"31"114;
%"TAP"
"1","(-1500,2950)","0","standard","I96";
;
CDS_LIB"standard"
BODY_TYPE"PLUMBING"
HDL_TAP"TRUE";
"B \NAC \NWC"10;
"S \NAC"
BN"2"117;
%"TAP"
"1","(-1500,2900)","0","standard","I97";
;
CDS_LIB"standard"
BODY_TYPE"PLUMBING"
HDL_TAP"TRUE";
"B \NAC \NWC"10;
"S \NAC"
BN"1"116;
%"TAP"
"1","(-1500,3050)","0","standard","I98";
;
CDS_LIB"standard"
BODY_TYPE"PLUMBING"
HDL_TAP"TRUE";
"B \NAC \NWC"10;
"S \NAC"
BN"4"119;
%"TAP"
"1","(-1500,3100)","0","standard","I99";
;
CDS_LIB"standard"
BODY_TYPE"PLUMBING"
HDL_TAP"TRUE";
"B \NAC \NWC"10;
"S \NAC"
BN"5"120;
END.
